# T6G (Grand Teton) — schematic netlist excerpt (pin names and nets, part order shuffled) for the footprints in the layout excerpt that follows; sources: Cadence DE-HDL packaged netlist, KiCad conversion of 04192023_DAF0TMB3IC0_F0TG_MB_C_brd_V02_OCP.brd

C1957  Q_CAP  0.1UF 25V 10% X7R  pkg 0402  page 128 : A = P3V3_AUX ; B = GND
R8305  Q_RES  0 5% CHIP  pkg 0402LF  page 28 : A = CLK_100M_CPU0_CLK13_R_DP ; B = CLK_100M_CPU0_CLK13_DP

(kicad_pcb
	(version 20260206)
	(generator "pcbnew")
	(generator_version "10.0")
	(general
		(thickness 1.6)
		(legacy_teardrops no)
	)
	(paper "A4")
	(title_block
		(title "04192023_DAF0TMB3IC0_F0TG_MB_C_brd_V02_OCP.brd")
		(comment 1 "Grand Teton / footprints 4450-4451 of 8354")
	)
	(layers
		(0 "F.Cu" signal "TOP")
		(4 "In1.Cu" signal "GND")
		(6 "In2.Cu" signal "IN1")
		(8 "In3.Cu" signal "GND1")
		(10 "In4.Cu" signal "IN2")
		(12 "In5.Cu" signal "GND2")
		(14 "In6.Cu" signal "IN3")
		(16 "In7.Cu" signal "GND3")
		(18 "In8.Cu" signal "VCC")
		(20 "In9.Cu" signal "VCC1")
		(22 "In10.Cu" signal "GND4")
		(24 "In11.Cu" signal "IN4")
		(26 "In12.Cu" signal "GND5")
		(28 "In13.Cu" signal "IN5")
		(30 "In14.Cu" signal "GND6")
		(32 "In15.Cu" signal "IN6")
		(34 "In16.Cu" signal "GND7")
		(2 "B.Cu" signal "BOTTOM")
		(9 "F.Adhes" user "F.Adhesive")
		(11 "B.Adhes" user "B.Adhesive")
		(13 "F.Paste" user "Package Geometry/Pastemask Top")
		(15 "B.Paste" user "Package Geometry/Pastemask Bottom")
		(5 "F.SilkS" user "Ref Des/Silkscreen Top")
		(7 "B.SilkS" user "Ref Des/Silkscreen Bottom")
		(1 "F.Mask" user "Board Geometry/Soldermask Top")
		(3 "B.Mask" user "Board Geometry/Soldermask Bottom")
		(17 "Dwgs.User" user "User.Drawings")
		(19 "Cmts.User" user "User.Comments")
		(21 "Eco1.User" user "User.Eco1")
		(23 "Eco2.User" user "User.Eco2")
		(25 "Edge.Cuts" user "Board Geometry/Outline")
		(27 "Margin" user)
		(31 "F.CrtYd" user "Package Geometry/Place Bound Top")
		(29 "B.CrtYd" user "Package Geometry/Place Bound Bottom")
		(35 "F.Fab" user "Ref Des/Assembly Top")
		(33 "B.Fab" user "Ref Des/Assembly Bottom")
	)
	(footprint ""
		(layer "F.Cu")
		(at 360.987594 -320.132964 90)
		(property "Reference" "R8305"
			(at 0 0 90)
			(layer "F.SilkS")
			(hide yes)
			(effects
				(font
					(size 1.27 1.27)
				)
			)
		)
		(property "Value" ""
			(at 0 0 90)
			(layer "F.Fab")
			(effects
				(font
					(size 1.27 1.27)
				)
			)
		)
		(duplicate_pad_numbers_are_jumpers no)
		(fp_line
			(start -0.372364 -0.4064)
			(end 0.364236 -0.4064)
			(stroke
				(width 0.1524)
				(type default)
			)
			(layer "F.SilkS")
		)
		(fp_line
			(start 0.7874 0.073406)
			(end 0.7874 0.4064)
			(stroke
				(width 0.1524)
				(type default)
			)
			(layer "F.SilkS")
		)
		(fp_line
			(start 0.7874 0.4064)
			(end -0.7874 0.4064)
			(stroke
				(width 0.1524)
				(type default)
			)
			(layer "F.SilkS")
		)
		(fp_line
			(start -0.7874 0.4064)
			(end -0.7874 0.022606)
			(stroke
				(width 0.1524)
				(type default)
			)
			(layer "F.SilkS")
		)
		(fp_line
			(start -0.12065 -0.305054)
			(end -0.12065 -0.2794)
			(stroke
				(width 0.1)
				(type default)
			)
			(layer "F.Fab")
		)
		(fp_line
			(start -0.67945 -0.305054)
			(end -0.12065 -0.305054)
			(stroke
				(width 0.1)
				(type default)
			)
			(layer "F.Fab")
		)
		(fp_line
			(start 0.67945 -0.3048)
			(end 0.67945 0.3048)
			(stroke
				(width 0.1)
				(type default)
			)
			(layer "F.Fab")
		)
		(fp_line
			(start 0.12065 -0.3048)
			(end 0.67945 -0.3048)
			(stroke
				(width 0.1)
				(type default)
			)
			(layer "F.Fab")
		)
		(fp_line
			(start 0.12065 -0.2794)
			(end 0.12065 -0.3048)
			(stroke
				(width 0.1)
				(type default)
			)
			(layer "F.Fab")
		)
		(fp_line
			(start -0.12065 -0.2794)
			(end 0.12065 -0.2794)
			(stroke
				(width 0.1)
				(type default)
			)
			(layer "F.Fab")
		)
		(fp_line
			(start 0.120396 0.2794)
			(end -0.12065 0.2794)
			(stroke
				(width 0.1)
				(type default)
			)
			(layer "F.Fab")
		)
		(fp_line
			(start -0.12065 0.2794)
			(end -0.12065 0.3048)
			(stroke
				(width 0.1)
				(type default)
			)
			(layer "F.Fab")
		)
		(fp_line
			(start 0.67945 0.3048)
			(end 0.120396 0.3048)
			(stroke
				(width 0.1)
				(type default)
			)
			(layer "F.Fab")
		)
		(fp_line
			(start 0.120396 0.3048)
			(end 0.120396 0.2794)
			(stroke
				(width 0.1)
				(type default)
			)
			(layer "F.Fab")
		)
		(fp_line
			(start -0.12065 0.3048)
			(end -0.67945 0.3048)
			(stroke
				(width 0.1)
				(type default)
			)
			(layer "F.Fab")
		)
		(fp_line
			(start -0.67945 0.3048)
			(end -0.67945 -0.305054)
			(stroke
				(width 0.1)
				(type default)
			)
			(layer "F.Fab")
		)
		(pad "1" smd circle
			(at -0.40005 0 90)
			(size 0 0)
			(layers "F.Cu" "F.Mask" "F.Paste")
			(net "CLK_100M_CPU0_CLK13_R_DP")
		)
		(pad "2" smd circle
			(at 0.40005 0 90)
			(size 0 0)
			(layers "F.Cu" "F.Mask" "F.Paste")
			(net "CLK_100M_CPU0_CLK13_DP")
		)
	)
	(footprint ""
		(layer "F.Cu")
		(at 53.594 -435.229 -90)
		(property "Reference" "C1957"
			(at 0 0 270)
			(layer "F.SilkS")
			(hide yes)
			(effects
				(font
					(size 1.27 1.27)
				)
			)
		)
		(property "Value" ""
			(at 0 0 270)
			(layer "F.Fab")
			(effects
				(font
					(size 1.27 1.27)
				)
			)
		)
		(duplicate_pad_numbers_are_jumpers no)
		(fp_line
			(start -0.7874 0.4064)
			(end -0.7874 -0.4064)
			(stroke
				(width 0.1524)
				(type default)
			)
			(layer "F.SilkS")
		)
		(fp_line
			(start 0.7874 0.4064)
			(end -0.7874 0.4064)
			(stroke
				(width 0.1524)
				(type default)
			)
			(layer "F.SilkS")
		)
		(fp_line
			(start -0.7874 -0.4064)
			(end 0.7874 -0.4064)
			(stroke
				(width 0.1524)
				(type default)
			)
			(layer "F.SilkS")
		)
		(fp_line
			(start 0.7874 -0.4064)
			(end 0.7874 0.4064)
			(stroke
				(width 0.1524)
				(type default)
			)
			(layer "F.SilkS")
		)
		(fp_line
			(start -0.67945 0.3048)
			(end -0.67945 -0.305054)
			(stroke
				(width 0.1)
				(type default)
			)
			(layer "F.Fab")
		)
		(fp_line
			(start -0.12065 0.3048)
			(end -0.67945 0.3048)
			(stroke
				(width 0.1)
				(type default)
			)
			(layer "F.Fab")
		)
		(fp_line
			(start 0.120396 0.3048)
			(end 0.120396 0.2794)
			(stroke
				(width 0.1)
				(type default)
			)
			(layer "F.Fab")
		)
		(fp_line
			(start 0.67945 0.3048)
			(end 0.120396 0.3048)
			(stroke
				(width 0.1)
				(type default)
			)
			(layer "F.Fab")
		)
		(fp_line
			(start -0.12065 0.2794)
			(end -0.12065 0.3048)
			(stroke
				(width 0.1)
				(type default)
			)
			(layer "F.Fab")
		)
		(fp_line
			(start 0.120396 0.2794)
			(end -0.12065 0.2794)
			(stroke
				(width 0.1)
				(type default)
			)
			(layer "F.Fab")
		)
		(fp_line
			(start -0.12065 -0.2794)
			(end 0.12065 -0.2794)
			(stroke
				(width 0.1)
				(type default)
			)
			(layer "F.Fab")
		)
		(fp_line
			(start 0.12065 -0.2794)
			(end 0.12065 -0.3048)
			(stroke
				(width 0.1)
				(type default)
			)
			(layer "F.Fab")
		)
		(fp_line
			(start 0.12065 -0.3048)
			(end 0.67945 -0.3048)
			(stroke
				(width 0.1)
				(type default)
			)
			(layer "F.Fab")
		)
		(fp_line
			(start 0.67945 -0.3048)
			(end 0.67945 0.3048)
			(stroke
				(width 0.1)
				(type default)
			)
			(layer "F.Fab")
		)
		(fp_line
			(start -0.67945 -0.305054)
			(end -0.12065 -0.305054)
			(stroke
				(width 0.1)
				(type default)
			)
			(layer "F.Fab")
		)
		(fp_line
			(start -0.12065 -0.305054)
			(end -0.12065 -0.2794)
			(stroke
				(width 0.1)
				(type default)
			)
			(layer "F.Fab")
		)
		(pad "1" smd circle
			(at -0.40005 0 270)
			(size 0 0)
			(layers "F.Cu" "F.Mask" "F.Paste")
			(net "P3V3_AUX")
		)
		(pad "2" smd circle
			(at 0.40005 0 270)
			(size 0 0)
			(layers "F.Cu" "F.Mask" "F.Paste")
			(net "GND")
		)
	)
)
